(kicad_pcb
	(version 20240108)
	(generator "pcbnew")
	(generator_version "8.0")
	(general
		(thickness 1.62)
		(legacy_teardrops no)
	)
	(paper "A4")
	(title_block
		(title "Jetson Orin Baseboard")
		(date "2025-03-12")
		(rev "1.3.4")
		(company "Antmicro Ltd")
		(comment 1 "www.antmicro.com")
		(comment 9 "footprints 104-108 of 677")
	)
	(layers
		(0 "F.Cu" signal)
		(1 "In1.Cu" signal)
		(2 "In2.Cu" signal)
		(3 "In3.Cu" signal)
		(4 "In4.Cu" jumper)
		(5 "In5.Cu" signal)
		(6 "In6.Cu" signal)
		(31 "B.Cu" signal)
		(32 "B.Adhes" user "B.Adhesive")
		(33 "F.Adhes" user "F.Adhesive")
		(34 "B.Paste" user)
		(35 "F.Paste" user)
		(36 "B.SilkS" user "B.Silkscreen")
		(37 "F.SilkS" user "F.Silkscreen")
		(38 "B.Mask" user)
		(39 "F.Mask" user)
		(40 "Dwgs.User" user "User.Drawings")
		(41 "Cmts.User" user "User.Comments")
		(42 "Eco1.User" user "User.Eco1")
		(43 "Eco2.User" user "User.Eco2")
		(44 "Edge.Cuts" user)
		(45 "Margin" user)
		(46 "B.CrtYd" user "B.Courtyard")
		(47 "F.CrtYd" user "F.Courtyard")
		(48 "B.Fab" user)
		(49 "F.Fab" user)
	)
	(footprint "antmicro-footprints:XDFN-2_1x0.60mm"
		(layer "F.Cu")
		(at 147.45 84.3 90)
		(property "Reference" "D45"
			(at 5.47 -0.15 0)
			(layer "F.SilkS")
			(effects
				(font
					(size 0.7 0.7)
					(thickness 0.15)
				)
				(justify left bottom)
			)
		)
		(property "Value" "TPD1E0B04_XDFN-2"
			(at 0 1.5 90)
			(layer "F.Fab")
			(effects
				(font
					(size 0.7 0.7)
					(thickness 0.15)
				)
				(justify left bottom)
			)
		)
		(property "Footprint" "antmicro-footprints:XDFN-2_1x0.60mm"
			(at 0 0 90)
			(layer "F.Fab")
			(hide yes)
			(effects
				(font
					(size 1.27 1.27)
					(thickness 0.15)
				)
			)
		)
		(property "Datasheet" "https://www.ti.com/general/docs/suppproductinfo.tsp?distId=26&gotoUrl=https://www.ti.com/lit/gpn/tpd1e0b04"
			(at 0 0 90)
			(layer "F.Fab")
			(hide yes)
			(effects
				(font
					(size 1.27 1.27)
					(thickness 0.15)
				)
			)
		)
		(property "MPN" "TPD1E0B04DPYR"
			(at 231.75 -63.15 0)
			(layer "F.Fab")
			(hide yes)
			(effects
				(font
					(size 1 1)
					(thickness 0.15)
				)
			)
		)
		(property "Manufacturer" "Texas Instruments"
			(at 231.75 -63.15 0)
			(layer "F.Fab")
			(hide yes)
			(effects
				(font
					(size 1 1)
					(thickness 0.15)
				)
			)
		)
		(property "Author" "Antmicro"
			(at 231.75 -63.15 0)
			(layer "F.Fab")
			(hide yes)
			(effects
				(font
					(size 1 1)
					(thickness 0.15)
				)
			)
		)
		(property "License" "Apache-2.0"
			(at 231.75 -63.15 0)
			(layer "F.Fab")
			(hide yes)
			(effects
				(font
					(size 1 1)
					(thickness 0.15)
				)
			)
		)
		(sheetname "Peripherals")
		(sheetfile "peripherals.kicad_sch")
		(attr smd)
		(fp_rect
			(start -0.725 -0.475)
			(end 0.725 0.475)
			(stroke
				(width 0.05)
				(type solid)
			)
			(fill none)
			(layer "F.CrtYd")
		)
		(fp_rect
			(start -0.55 -0.35)
			(end 0.55 0.35)
			(stroke
				(width 0.15)
				(type solid)
			)
			(fill none)
			(layer "F.Fab")
		)
		(fp_text user "License: Apache-2.0"
			(at -0.8 5.6 90)
			(layer "F.Fab")
			(hide yes)
			(effects
				(font
					(size 0.7 0.7)
					(thickness 0.15)
				)
				(justify left bottom)
			)
		)
		(fp_text user "${REFERENCE}"
			(at -0.8 3.2 90)
			(layer "F.Fab")
			(hide yes)
			(effects
				(font
					(size 0.7 0.7)
					(thickness 0.15)
				)
				(justify left bottom)
			)
		)
		(fp_text user "Author: Antmicro"
			(at -0.8 4.4 90)
			(layer "F.Fab")
			(hide yes)
			(effects
				(font
					(size 0.7 0.7)
					(thickness 0.15)
				)
				(justify left bottom)
			)
		)
		(pad "1" smd roundrect
			(at -0.351 0 90)
			(size 0.3 0.5)
			(layers "F.Cu" "F.Paste" "F.Mask")
			(roundrect_rratio 0.25)
			(net 172 "PCIE2_RX1_N")
			(pinfunction "C")
			(pintype "passive")
		)
		(pad "2" smd roundrect
			(at 0.349 0 90)
			(size 0.3 0.5)
			(layers "F.Cu" "F.Paste" "F.Mask")
			(roundrect_rratio 0.25)
			(net 1 "GND")
			(pinfunction "A")
			(pintype "passive")
		)
	)
	(footprint "antmicro-footprints:C_0402_1005Metric"
		(layer "F.Cu")
		(at 81.9 107 180)
		(descr "Capacitor SMD 0402")
		(tags "capacitor SMD 0402")
		(property "Reference" "C143"
			(at -0.8 -0.4 180)
			(layer "F.SilkS")
			(effects
				(font
					(size 0.7 0.7)
					(thickness 0.15)
				)
				(justify left bottom)
			)
		)
		(property "Value" "C_100n_0402"
			(at 0 1.4 180)
			(layer "F.Fab")
			(effects
				(font
					(size 0.7 0.7)
					(thickness 0.15)
				)
				(justify left bottom)
			)
		)
		(property "Footprint" "antmicro-footprints:C_0402_1005Metric"
			(at 0 0 180)
			(layer "F.Fab")
			(hide yes)
			(effects
				(font
					(size 1.27 1.27)
					(thickness 0.15)
				)
			)
		)
		(property "Datasheet" "https://www.murata.com/products/productdetail?partno=GRM155R61H104KE14%23"
			(at 0 0 180)
			(layer "F.Fab")
			(hide yes)
			(effects
				(font
					(size 1.27 1.27)
					(thickness 0.15)
				)
			)
		)
		(property "Author" "Antmicro"
			(at 163.8 214 0)
			(layer "F.Fab")
			(hide yes)
			(effects
				(font
					(size 1 1)
					(thickness 0.15)
				)
			)
		)
		(property "Dielectric" "X5R"
			(at 163.8 214 0)
			(layer "F.Fab")
			(hide yes)
			(effects
				(font
					(size 1 1)
					(thickness 0.15)
				)
			)
		)
		(property "License" "Apache-2.0"
			(at 163.8 214 0)
			(layer "F.Fab")
			(hide yes)
			(effects
				(font
					(size 1 1)
					(thickness 0.15)
				)
			)
		)
		(property "MPN" "GRM155R61H104KE14D"
			(at 163.8 214 0)
			(layer "F.Fab")
			(hide yes)
			(effects
				(font
					(size 1 1)
					(thickness 0.15)
				)
			)
		)
		(property "Manufacturer" "Murata"
			(at 163.8 214 0)
			(layer "F.Fab")
			(hide yes)
			(effects
				(font
					(size 1 1)
					(thickness 0.15)
				)
			)
		)
		(property "Val" "100n"
			(at 163.8 214 0)
			(layer "F.Fab")
			(hide yes)
			(effects
				(font
					(size 1 1)
					(thickness 0.15)
				)
			)
		)
		(property "Voltage" "50V"
			(at 163.8 214 0)
			(layer "F.Fab")
			(hide yes)
			(effects
				(font
					(size 1 1)
					(thickness 0.15)
				)
			)
		)
		(sheetname "USB Debug, DP")
		(sheetfile "usb.kicad_sch")
		(attr smd)
		(fp_rect
			(start -0.925 -0.47)
			(end 0.925 0.47)
			(stroke
				(width 0.05)
				(type default)
			)
			(fill none)
			(layer "F.CrtYd")
		)
		(fp_line
			(start 0.504 0.248)
			(end -0.494 0.248)
			(stroke
				(width 0.15)
				(type solid)
			)
			(layer "F.Fab")
		)
		(fp_line
			(start 0.504 -0.25)
			(end 0.504 0.248)
			(stroke
				(width 0.15)
				(type solid)
			)
			(layer "F.Fab")
		)
		(fp_line
			(start -0.494 0.248)
			(end -0.494 -0.25)
			(stroke
				(width 0.15)
				(type solid)
			)
			(layer "F.Fab")
		)
		(fp_line
			(start -0.494 -0.25)
			(end 0.504 -0.25)
			(stroke
				(width 0.15)
				(type solid)
			)
			(layer "F.Fab")
		)
		(fp_text user "License: Apache-2.0"
			(at -0.932 5.17 180)
			(layer "F.Fab")
			(hide yes)
			(effects
				(font
					(size 0.7 0.7)
					(thickness 0.15)
				)
				(justify left bottom)
			)
		)
		(fp_text user "${REFERENCE}"
			(at -0.932 3.168 180)
			(layer "F.Fab")
			(hide yes)
			(effects
				(font
					(size 0.7 0.7)
					(thickness 0.15)
				)
				(justify left bottom)
			)
		)
		(fp_text user "Author: Antmicro"
			(at -0.932 4.17 180)
			(layer "F.Fab")
			(hide yes)
			(effects
				(font
					(size 0.7 0.7)
					(thickness 0.15)
				)
				(justify left bottom)
			)
		)
		(pad "1" smd roundrect
			(at -0.48 0 180)
			(size 0.59 0.64)
			(layers "F.Cu" "F.Paste" "F.Mask")
			(roundrect_rratio 0.25)
			(net 56 "USBSS0_RX_N")
			(pintype "passive")
		)
		(pad "2" smd roundrect
			(at 0.48 0 180)
			(size 0.59 0.64)
			(layers "F.Cu" "F.Paste" "F.Mask")
			(roundrect_rratio 0.25)
			(net 193 "/USB Debug, DP/USBSS0_RX_C_P")
			(pintype "passive")
		)
	)
	(footprint "antmicro-footprints:R_0402_1005Metric"
		(layer "F.Cu")
		(at 96.65 98.05 180)
		(descr "Resistor SMD 0402")
		(tags "resistor SMD 0402")
		(property "Reference" "R163"
			(at 1.4 0.45 180)
			(layer "F.SilkS")
			(effects
				(font
					(size 0.7 0.7)
					(thickness 0.15)
				)
				(justify left bottom)
			)
		)
		(property "Value" "R_10k_0402"
			(at 0 1.4 180)
			(layer "F.Fab")
			(effects
				(font
					(size 0.7 0.7)
					(thickness 0.15)
				)
				(justify left bottom)
			)
		)
		(property "Footprint" "antmicro-footprints:R_0402_1005Metric"
			(at 0 0 180)
			(layer "F.Fab")
			(hide yes)
			(effects
				(font
					(size 1.27 1.27)
					(thickness 0.15)
				)
			)
		)
		(property "Datasheet" "https://www.bourns.com/docs/product-datasheets/cr.pdf"
			(at 0 0 180)
			(layer "F.Fab")
			(hide yes)
			(effects
				(font
					(size 1.27 1.27)
					(thickness 0.15)
				)
			)
		)
		(property "Author" "Antmicro"
			(at 193.3 196.1 0)
			(layer "F.Fab")
			(hide yes)
			(effects
				(font
					(size 1 1)
					(thickness 0.15)
				)
			)
		)
		(property "License" "Apache-2.0"
			(at 193.3 196.1 0)
			(layer "F.Fab")
			(hide yes)
			(effects
				(font
					(size 1 1)
					(thickness 0.15)
				)
			)
		)
		(property "MPN" "CR0402-FX-1002GLF"
			(at 193.3 196.1 0)
			(layer "F.Fab")
			(hide yes)
			(effects
				(font
					(size 1 1)
					(thickness 0.15)
				)
			)
		)
		(property "Manufacturer" "Bourns"
			(at 193.3 196.1 0)
			(layer "F.Fab")
			(hide yes)
			(effects
				(font
					(size 1 1)
					(thickness 0.15)
				)
			)
		)
		(property "Tolerance" "1%"
			(at 193.3 196.1 0)
			(layer "F.Fab")
			(hide yes)
			(effects
				(font
					(size 1 1)
					(thickness 0.15)
				)
			)
		)
		(property "Val" "10k"
			(at 193.3 196.1 0)
			(layer "F.Fab")
			(hide yes)
			(effects
				(font
					(size 1 1)
					(thickness 0.15)
				)
			)
		)
		(sheetname "CSI")
		(sheetfile "csi.kicad_sch")
		(attr smd)
		(fp_rect
			(start -0.925 -0.47)
			(end 0.925 0.47)
			(stroke
				(width 0.05)
				(type default)
			)
			(fill none)
			(layer "F.CrtYd")
		)
		(fp_rect
			(start -0.5 -0.25)
			(end 0.5 0.25)
			(stroke
				(width 0.15)
				(type solid)
			)
			(fill none)
			(layer "F.Fab")
		)
		(fp_text user "${REFERENCE}"
			(at -0.95 3.168 180)
			(layer "F.Fab")
			(hide yes)
			(effects
				(font
					(size 0.7 0.7)
					(thickness 0.15)
				)
				(justify left bottom)
			)
		)
		(fp_text user "Author: Antmicro"
			(at -0.95 4.169 180)
			(layer "F.Fab")
			(hide yes)
			(effects
				(font
					(size 0.7 0.7)
					(thickness 0.15)
				)
				(justify left bottom)
			)
		)
		(fp_text user "License: Apache-2.0"
			(at -0.95 5.169 180)
			(layer "F.Fab")
			(hide yes)
			(effects
				(font
					(size 0.7 0.7)
					(thickness 0.15)
				)
				(justify left bottom)
			)
		)
		(pad "1" smd roundrect
			(at -0.48 0 180)
			(size 0.59 0.64)
			(layers "F.Cu" "F.Paste" "F.Mask")
			(roundrect_rratio 0.25)
			(net 112 "+1V8")
			(pintype "passive")
		)
		(pad "2" smd roundrect
			(at 0.48 0 180)
			(size 0.59 0.64)
			(layers "F.Cu" "F.Paste" "F.Mask")
			(roundrect_rratio 0.25)
			(net 324 "/CSI/I2C_MUX_RESET")
			(pintype "passive")
		)
	)
	(footprint "antmicro-footprints:XDFN-2_1x0.60mm"
		(layer "F.Cu")
		(at 136.27 92.63 -90)
		(property "Reference" "D21"
			(at 0.298 -0.402 180)
			(layer "F.SilkS")
			(effects
				(font
					(size 0.7 0.7)
					(thickness 0.15)
				)
				(justify left bottom)
			)
		)
		(property "Value" "TPD1E0B04_XDFN-2"
			(at 0 1.5 -90)
			(layer "F.Fab")
			(effects
				(font
					(size 0.7 0.7)
					(thickness 0.15)
				)
				(justify left bottom)
			)
		)
		(property "Footprint" "antmicro-footprints:XDFN-2_1x0.60mm"
			(at 0 0 -90)
			(layer "F.Fab")
			(hide yes)
			(effects
				(font
					(size 1.27 1.27)
					(thickness 0.15)
				)
			)
		)
		(property "Datasheet" "https://www.ti.com/general/docs/suppproductinfo.tsp?distId=26&gotoUrl=https://www.ti.com/lit/gpn/tpd1e0b04"
			(at 0 0 -90)
			(layer "F.Fab")
			(hide yes)
			(effects
				(font
					(size 1.27 1.27)
					(thickness 0.15)
				)
			)
		)
		(property "MPN" "TPD1E0B04DPYR"
			(at 43.64 228.9 0)
			(layer "F.Fab")
			(hide yes)
			(effects
				(font
					(size 1 1)
					(thickness 0.15)
				)
			)
		)
		(property "Manufacturer" "Texas Instruments"
			(at 43.64 228.9 0)
			(layer "F.Fab")
			(hide yes)
			(effects
				(font
					(size 1 1)
					(thickness 0.15)
				)
			)
		)
		(property "Author" "Antmicro"
			(at 43.64 228.9 0)
			(layer "F.Fab")
			(hide yes)
			(effects
				(font
					(size 1 1)
					(thickness 0.15)
				)
			)
		)
		(property "License" "Apache-2.0"
			(at 43.64 228.9 0)
			(layer "F.Fab")
			(hide yes)
			(effects
				(font
					(size 1 1)
					(thickness 0.15)
				)
			)
		)
		(sheetname "Peripherals")
		(sheetfile "peripherals.kicad_sch")
		(attr smd)
		(fp_rect
			(start -0.725 -0.475)
			(end 0.725 0.475)
			(stroke
				(width 0.05)
				(type solid)
			)
			(fill none)
			(layer "F.CrtYd")
		)
		(fp_rect
			(start -0.55 -0.35)
			(end 0.55 0.35)
			(stroke
				(width 0.15)
				(type solid)
			)
			(fill none)
			(layer "F.Fab")
		)
		(fp_text user "Author: Antmicro"
			(at -0.8 4.4 -90)
			(layer "F.Fab")
			(hide yes)
			(effects
				(font
					(size 0.7 0.7)
					(thickness 0.15)
				)
				(justify left bottom)
			)
		)
		(fp_text user "${REFERENCE}"
			(at -0.8 3.2 -90)
			(layer "F.Fab")
			(hide yes)
			(effects
				(font
					(size 0.7 0.7)
					(thickness 0.15)
				)
				(justify left bottom)
			)
		)
		(fp_text user "License: Apache-2.0"
			(at -0.8 5.6 -90)
			(layer "F.Fab")
			(hide yes)
			(effects
				(font
					(size 0.7 0.7)
					(thickness 0.15)
				)
				(justify left bottom)
			)
		)
		(pad "1" smd roundrect
			(at -0.351 0 270)
			(size 0.3 0.5)
			(layers "F.Cu" "F.Paste" "F.Mask")
			(roundrect_rratio 0.25)
			(net 414 "/Peripherals/USBSS2_TX_CONN_P")
			(pinfunction "C")
			(pintype "passive")
		)
		(pad "2" smd roundrect
			(at 0.349 0 270)
			(size 0.3 0.5)
			(layers "F.Cu" "F.Paste" "F.Mask")
			(roundrect_rratio 0.25)
			(net 1 "GND")
			(pinfunction "A")
			(pintype "passive")
		)
	)
	(footprint "antmicro-footprints:R_Array_4x0201_Panasonic_EXB18V"
		(layer "F.Cu")
		(at 120.3468 112.2)
		(property "Reference" "R21"
			(at -1.0968 -0.65 180)
			(layer "F.SilkS")
			(effects
				(font
					(size 0.7 0.7)
					(thickness 0.15)
				)
				(justify left bottom)
			)
		)
		(property "Value" "R_4x0R_0201_array"
			(at -1.1 1.8 0)
			(layer "F.Fab")
			(effects
				(font
					(size 0.7 0.7)
					(thickness 0.15)
				)
				(justify left bottom)
			)
		)
		(property "Footprint" "antmicro-footprints:R_Array_4x0201_Panasonic_EXB18V"
			(at 0 0 0)
			(layer "F.Fab")
			(hide yes)
			(effects
				(font
					(size 1.27 1.27)
					(thickness 0.15)
				)
			)
		)
		(property "Datasheet" "http://industrial.panasonic.com/cdbs/www-data/pdf/AOC0000/AOC0000C14.pdf"
			(at 0 0 0)
			(layer "F.Fab")
			(hide yes)
			(effects
				(font
					(size 1.27 1.27)
					(thickness 0.15)
				)
			)
		)
		(property "Author" "Antmicro"
			(at 0 0 0)
			(layer "F.Fab")
			(hide yes)
			(effects
				(font
					(size 1 1)
					(thickness 0.15)
				)
			)
		)
		(property "License" "Apache-2.0"
			(at 0 0 0)
			(layer "F.Fab")
			(hide yes)
			(effects
				(font
					(size 1 1)
					(thickness 0.15)
				)
			)
		)
		(property "MPN" "EXB-18VR000X"
			(at 0 0 0)
			(layer "F.Fab")
			(hide yes)
			(effects
				(font
					(size 1 1)
					(thickness 0.15)
				)
			)
		)
		(property "Manufacturer" "Panasonic"
			(at 0 0 0)
			(layer "F.Fab")
			(hide yes)
			(effects
				(font
					(size 1 1)
					(thickness 0.15)
				)
			)
		)
		(property "Val" "4x0R_0201"
			(at 0 0 0)
			(layer "F.Fab")
			(hide yes)
			(effects
				(font
					(size 1 1)
					(thickness 0.15)
				)
			)
		)
		(sheetname "M.2")
		(sheetfile "m-2.kicad_sch")
		(attr smd)
		(fp_line
			(start -0.8 -0.45)
			(end -0.8 0.45)
			(stroke
				(width 0.12)
				(type solid)
			)
			(layer "F.SilkS")
		)
		(fp_line
			(start 0.8 -0.45)
			(end 0.8 0.45)
			(stroke
				(width 0.12)
				(type solid)
			)
			(layer "F.SilkS")
		)
		(fp_rect
			(start -0.898 -0.66)
			(end 0.898 0.65)
			(stroke
				(width 0.05)
				(type solid)
			)
			(fill none)
			(layer "F.CrtYd")
		)
		(fp_text user "License: Apache-2.0"
			(at -1.051 6 0)
			(layer "F.Fab")
			(hide yes)
			(effects
				(font
					(size 0.7 0.7)
					(thickness 0.15)
				)
				(justify left bottom)
			)
		)
		(fp_text user "Author: Antmicro"
			(at -1.051 4.599 0)
			(layer "F.Fab")
			(hide yes)
			(effects
				(font
					(size 0.7 0.7)
					(thickness 0.15)
				)
				(justify left bottom)
			)
		)
		(fp_text user "${REFERENCE}"
			(at -1.051 3.2 0)
			(layer "F.Fab")
			(hide yes)
			(effects
				(font
					(size 0.7 0.7)
					(thickness 0.15)
				)
				(justify left bottom)
			)
		)
		(pad "1" smd roundrect
			(at -0.6 0.298)
			(size 0.2 0.4)
			(layers "F.Cu" "F.Paste" "F.Mask")
			(roundrect_rratio 0.25)
			(net 470 "I2S1_SCLK")
			(pinfunction "R1.1")
			(pintype "passive")
		)
		(pad "2" smd roundrect
			(at -0.202 0.298)
			(size 0.2 0.4)
			(layers "F.Cu" "F.Paste" "F.Mask")
			(roundrect_rratio 0.25)
			(net 469 "I2S1_LRCK")
			(pinfunction "R2.1")
			(pintype "passive")
		)
		(pad "3" smd roundrect
			(at 0.2 0.298)
			(size 0.2 0.4)
			(layers "F.Cu" "F.Paste" "F.Mask")
			(roundrect_rratio 0.25)
			(net 468 "I2S1_SDIN")
			(pinfunction "R3.1")
			(pintype "passive")
		)
		(pad "4" smd roundrect
			(at 0.598 0.298)
			(size 0.2 0.4)
			(layers "F.Cu" "F.Paste" "F.Mask")
			(roundrect_rratio 0.25)
			(net 467 "I2S1_SDOUT")
			(pinfunction "R4.1")
			(pintype "passive")
		)
		(pad "5" smd roundrect
			(at 0.598 -0.3)
			(size 0.2 0.4)
			(layers "F.Cu" "F.Paste" "F.Mask")
			(roundrect_rratio 0.25)
			(net 178 "/M.2/M2_E_PCM_OUT")
			(pinfunction "R4.2")
			(pintype "passive")
		)
		(pad "6" smd roundrect
			(at 0.2 -0.3)
			(size 0.2 0.4)
			(layers "F.Cu" "F.Paste" "F.Mask")
			(roundrect_rratio 0.25)
			(net 651 "/M.2/M2_E_PCM_IN")
			(pinfunction "R3.2")
			(pintype "passive")
		)
		(pad "7" smd roundrect
			(at -0.202 -0.3)
			(size 0.2 0.4)
			(layers "F.Cu" "F.Paste" "F.Mask")
			(roundrect_rratio 0.25)
			(net 176 "/M.2/M2_E_PCM_SYNC")
			(pinfunction "R2.2")
			(pintype "passive")
		)
		(pad "8" smd roundrect
			(at -0.6 -0.3)
			(size 0.2 0.4)
			(layers "F.Cu" "F.Paste" "F.Mask")
			(roundrect_rratio 0.25)
			(net 170 "/M.2/M2_E_PCM_CLK")
			(pinfunction "R1.2")
			(pintype "passive")
		)
	)
)
